# T6G (Grand Teton) — schematic netlist excerpt (pin names and nets, part order shuffled) for the footprints in the layout excerpt that follows; sources: Cadence DE-HDL packaged netlist, KiCad conversion of 04192023_DAF0TMB3IC0_F0TG_MB_C_brd_V02_OCP.brd

R904  Q_RES  1K 1% EMPTY  pkg 0201LF  page 353 : A = P1V8_CPU1_RT_1D ; B = RT_CPU1_P3_ADDR2

Q9002  MOSFET_NCH_DUAL  PJT138K IC  pkg SOT363XD  page 123
  S1  = GND
  G1  = PRSNT_CABLE_GPU_A3_N
  D2  = PRSNT_CABLE_GPU_A3_ISO_N
  S2  = GND
  G2  = PRSNT_CABLE_GPU_A3
  D1  = PRSNT_CABLE_GPU_A3

R3602  Q_RES  10 1% CHIP  pkg 0402LF  page 236 : A = P3V3_OCP_SFF_R ; B = VSENSE_P3V3_INA230_1_INP

(kicad_pcb
	(version 20260206)
	(generator "pcbnew")
	(generator_version "10.0")
	(general
		(thickness 1.6)
		(legacy_teardrops no)
	)
	(paper "A4")
	(title_block
		(title "04192023_DAF0TMB3IC0_F0TG_MB_C_brd_V02_OCP.brd")
		(comment 1 "Grand Teton / footprints 1282-1284 of 8354")
	)
	(layers
		(0 "F.Cu" signal "TOP")
		(4 "In1.Cu" signal "GND")
		(6 "In2.Cu" signal "IN1")
		(8 "In3.Cu" signal "GND1")
		(10 "In4.Cu" signal "IN2")
		(12 "In5.Cu" signal "GND2")
		(14 "In6.Cu" signal "IN3")
		(16 "In7.Cu" signal "GND3")
		(18 "In8.Cu" signal "VCC")
		(20 "In9.Cu" signal "VCC1")
		(22 "In10.Cu" signal "GND4")
		(24 "In11.Cu" signal "IN4")
		(26 "In12.Cu" signal "GND5")
		(28 "In13.Cu" signal "IN5")
		(30 "In14.Cu" signal "GND6")
		(32 "In15.Cu" signal "IN6")
		(34 "In16.Cu" signal "GND7")
		(2 "B.Cu" signal "BOTTOM")
		(9 "F.Adhes" user "F.Adhesive")
		(11 "B.Adhes" user "B.Adhesive")
		(13 "F.Paste" user "Package Geometry/Pastemask Top")
		(15 "B.Paste" user "Package Geometry/Pastemask Bottom")
		(5 "F.SilkS" user "Ref Des/Silkscreen Top")
		(7 "B.SilkS" user "Ref Des/Silkscreen Bottom")
		(1 "F.Mask" user "Board Geometry/Soldermask Top")
		(3 "B.Mask" user "Board Geometry/Soldermask Bottom")
		(17 "Dwgs.User" user "User.Drawings")
		(19 "Cmts.User" user "User.Comments")
		(21 "Eco1.User" user "User.Eco1")
		(23 "Eco2.User" user "User.Eco2")
		(25 "Edge.Cuts" user "Board Geometry/Outline")
		(27 "Margin" user)
		(31 "F.CrtYd" user "Package Geometry/Place Bound Top")
		(29 "B.CrtYd" user "Package Geometry/Place Bound Bottom")
		(35 "F.Fab" user "Ref Des/Assembly Top")
		(33 "B.Fab" user "Ref Des/Assembly Bottom")
	)
	(footprint ""
		(layer "F.Cu")
		(at 363.044486 -406.172416 180)
		(property "Reference" "Q9002"
			(at -3.329432 -1.883156 90)
			(unlocked yes)
			(layer "F.SilkS")
			(effects
				(font
					(size 0.7874 0.5842)
					(thickness 0.1524)
				)
				(justify left)
			)
		)
		(property "Value" ""
			(at 0 0 180)
			(layer "F.Fab")
			(effects
				(font
					(size 1.27 1.27)
				)
			)
		)
		(duplicate_pad_numbers_are_jumpers no)
		(fp_line
			(start 1.332738 1.100074)
			(end -1.332738 1.100074)
			(stroke
				(width 0.1524)
				(type default)
			)
			(layer "F.SilkS")
		)
		(fp_line
			(start 1.332738 -1.100074)
			(end 1.332738 1.100074)
			(stroke
				(width 0.1524)
				(type default)
			)
			(layer "F.SilkS")
		)
		(fp_line
			(start 0.4826 -1.100074)
			(end 1.332738 -1.100074)
			(stroke
				(width 0.1524)
				(type default)
			)
			(layer "F.SilkS")
		)
		(fp_line
			(start 0 -0.541274)
			(end 0.4826 -1.100074)
			(stroke
				(width 0.1524)
				(type default)
			)
			(layer "F.SilkS")
		)
		(fp_line
			(start -0.4826 -1.100074)
			(end 0 -0.541274)
			(stroke
				(width 0.1524)
				(type default)
			)
			(layer "F.SilkS")
		)
		(fp_line
			(start -1.332738 1.100074)
			(end -1.332738 -1.100074)
			(stroke
				(width 0.1524)
				(type default)
			)
			(layer "F.SilkS")
		)
		(fp_line
			(start -1.332738 -1.100074)
			(end -0.4826 -1.100074)
			(stroke
				(width 0.1524)
				(type default)
			)
			(layer "F.SilkS")
		)
		(fp_poly
			(pts
				(xy -2.659634 -0.318262) (xy -2.659634 -1.020318) (xy -1.957578 -0.66929)
			)
			(stroke
				(width 0)
				(type default)
			)
			(fill yes)
			(layer "F.SilkS")
		)
		(fp_line
			(start 0.674878 1.100074)
			(end -0.674878 1.100074)
			(stroke
				(width 0.1)
				(type default)
			)
			(layer "F.Fab")
		)
		(fp_line
			(start 0.674878 -1.100074)
			(end 0.674878 1.100074)
			(stroke
				(width 0.1)
				(type default)
			)
			(layer "F.Fab")
		)
		(fp_line
			(start -0.674878 1.100074)
			(end -0.674878 -1.100074)
			(stroke
				(width 0.1)
				(type default)
			)
			(layer "F.Fab")
		)
		(fp_line
			(start -0.674878 -1.100074)
			(end 0.674878 -1.100074)
			(stroke
				(width 0.1)
				(type default)
			)
			(layer "F.Fab")
		)
		(fp_poly
			(pts
				(xy -2.2352 -0.298958) (xy -2.2352 -1.001014) (xy -1.533144 -0.649986)
			)
			(stroke
				(width 0)
				(type default)
			)
			(fill yes)
			(layer "F.Fab")
		)
		(pad "1" smd rect
			(at -0.94996 -0.649986 270)
			(size 0.4318 0.508)
			(layers "F.Cu" "F.Mask" "F.Paste")
			(net "GND")
		)
		(pad "2" smd rect
			(at -0.94996 0 270)
			(size 0.4318 0.508)
			(layers "F.Cu" "F.Mask" "F.Paste")
			(net "PRSNT_CABLE_GPU_A3_N")
		)
		(pad "3" smd rect
			(at -0.94996 0.649986 270)
			(size 0.4318 0.508)
			(layers "F.Cu" "F.Mask" "F.Paste")
			(net "PRSNT_CABLE_GPU_A3_ISO_N")
		)
		(pad "4" smd rect
			(at 0.94996 0.649986 270)
			(size 0.4318 0.508)
			(layers "F.Cu" "F.Mask" "F.Paste")
			(net "GND")
		)
		(pad "5" smd rect
			(at 0.94996 0 270)
			(size 0.4318 0.508)
			(layers "F.Cu" "F.Mask" "F.Paste")
			(net "PRSNT_CABLE_GPU_A3")
		)
		(pad "6" smd rect
			(at 0.94996 -0.649986 270)
			(size 0.4318 0.508)
			(layers "F.Cu" "F.Mask" "F.Paste")
			(net "PRSNT_CABLE_GPU_A3")
		)
	)
	(footprint ""
		(layer "F.Cu")
		(at 139.794742 -385.5212 90)
		(property "Reference" "R904"
			(at 0 0 90)
			(layer "F.SilkS")
			(hide yes)
			(effects
				(font
					(size 1.27 1.27)
				)
			)
		)
		(property "Value" ""
			(at 0 0 90)
			(layer "F.Fab")
			(effects
				(font
					(size 1.27 1.27)
				)
			)
		)
		(duplicate_pad_numbers_are_jumpers no)
		(fp_line
			(start 0.32512 -0.175006)
			(end 0.32512 0.175006)
			(stroke
				(width 0.1)
				(type default)
			)
			(layer "F.Fab")
		)
		(fp_line
			(start -0.32512 -0.175006)
			(end 0.32512 -0.175006)
			(stroke
				(width 0.1)
				(type default)
			)
			(layer "F.Fab")
		)
		(fp_line
			(start 0.32512 0.175006)
			(end -0.32512 0.175006)
			(stroke
				(width 0.1)
				(type default)
			)
			(layer "F.Fab")
		)
		(fp_line
			(start -0.32512 0.175006)
			(end -0.32512 -0.175006)
			(stroke
				(width 0.1)
				(type default)
			)
			(layer "F.Fab")
		)
		(pad "1" smd rect
			(at -0.2667 0 90)
			(size 0.3048 0.381)
			(layers "F.Cu" "F.Mask" "F.Paste")
			(net "P1V8_CPU1_RT_1D")
		)
		(pad "2" smd rect
			(at 0.2667 0 270)
			(size 0.3048 0.381)
			(layers "F.Cu" "F.Mask" "F.Paste")
			(net "RT_CPU1_P3_ADDR2")
		)
	)
	(footprint ""
		(layer "F.Cu")
		(at 432.636676 -93.922342)
		(property "Reference" "R3602"
			(at 0 0 0)
			(layer "F.SilkS")
			(hide yes)
			(effects
				(font
					(size 1.27 1.27)
				)
			)
		)
		(property "Value" ""
			(at 0 0 0)
			(layer "F.Fab")
			(effects
				(font
					(size 1.27 1.27)
				)
			)
		)
		(duplicate_pad_numbers_are_jumpers no)
		(fp_line
			(start -0.7874 -0.4064)
			(end 0.7874 -0.4064)
			(stroke
				(width 0.1524)
				(type default)
			)
			(layer "F.SilkS")
		)
		(fp_line
			(start -0.7874 0.4064)
			(end -0.7874 -0.4064)
			(stroke
				(width 0.1524)
				(type default)
			)
			(layer "F.SilkS")
		)
		(fp_line
			(start 0.7874 -0.4064)
			(end 0.7874 0.4064)
			(stroke
				(width 0.1524)
				(type default)
			)
			(layer "F.SilkS")
		)
		(fp_line
			(start 0.7874 0.4064)
			(end -0.7874 0.4064)
			(stroke
				(width 0.1524)
				(type default)
			)
			(layer "F.SilkS")
		)
		(fp_line
			(start -0.67945 -0.305054)
			(end -0.12065 -0.305054)
			(stroke
				(width 0.1)
				(type default)
			)
			(layer "F.Fab")
		)
		(fp_line
			(start -0.67945 0.3048)
			(end -0.67945 -0.305054)
			(stroke
				(width 0.1)
				(type default)
			)
			(layer "F.Fab")
		)
		(fp_line
			(start -0.12065 -0.305054)
			(end -0.12065 -0.2794)
			(stroke
				(width 0.1)
				(type default)
			)
			(layer "F.Fab")
		)
		(fp_line
			(start -0.12065 -0.2794)
			(end 0.12065 -0.2794)
			(stroke
				(width 0.1)
				(type default)
			)
			(layer "F.Fab")
		)
		(fp_line
			(start -0.12065 0.2794)
			(end -0.12065 0.3048)
			(stroke
				(width 0.1)
				(type default)
			)
			(layer "F.Fab")
		)
		(fp_line
			(start -0.12065 0.3048)
			(end -0.67945 0.3048)
			(stroke
				(width 0.1)
				(type default)
			)
			(layer "F.Fab")
		)
		(fp_line
			(start 0.120396 0.2794)
			(end -0.12065 0.2794)
			(stroke
				(width 0.1)
				(type default)
			)
			(layer "F.Fab")
		)
		(fp_line
			(start 0.120396 0.3048)
			(end 0.120396 0.2794)
			(stroke
				(width 0.1)
				(type default)
			)
			(layer "F.Fab")
		)
		(fp_line
			(start 0.12065 -0.3048)
			(end 0.67945 -0.3048)
			(stroke
				(width 0.1)
				(type default)
			)
			(layer "F.Fab")
		)
		(fp_line
			(start 0.12065 -0.2794)
			(end 0.12065 -0.3048)
			(stroke
				(width 0.1)
				(type default)
			)
			(layer "F.Fab")
		)
		(fp_line
			(start 0.67945 -0.3048)
			(end 0.67945 0.3048)
			(stroke
				(width 0.1)
				(type default)
			)
			(layer "F.Fab")
		)
		(fp_line
			(start 0.67945 0.3048)
			(end 0.120396 0.3048)
			(stroke
				(width 0.1)
				(type default)
			)
			(layer "F.Fab")
		)
		(pad "1" smd circle
			(at -0.40005 0)
			(size 0 0)
			(layers "F.Cu" "F.Mask" "F.Paste")
			(net "P3V3_OCP_SFF_R")
		)
		(pad "2" smd circle
			(at 0.40005 0)
			(size 0 0)
			(layers "F.Cu" "F.Mask" "F.Paste")
			(net "VSENSE_P3V3_INA230_1_INP")
		)
	)
)
